Altium Designer Pick and Place Locations
C:\Users\<user>\Desktop\WorkNotes\Projects\PTP\TimeCardNPI\HackDesign\WIP\ECAD\Project Outputs for Timingcard_PROJECT\Pick Place for TimeCard-DC-V8_EXP.csv

========================================================================================================================
File Design Information:

Date:       27/01/23
Time:       09:14
Revision:   Not in VersionControl
Variant:    No variations
Units used: mil

"Designator","Comment","Layer","Footprint","Center-X(mil)","Center-Y(mil)","Rotation","Description"
"R110","DNI_4.7K_0402","TopLayer","RESC1005X40X25LL05T05","677.165","-1177.165","180","Chip Resistor, 4.7 KOhm, +/- 1%, 0.1 W, -55 to 155 degC, 0402 (1005 Metric), RoHS, Tape and Reel"
"R109","4.7K_0402","TopLayer","RESC1005X40X25LL05T05","677.165","-1102.362","0","Chip Resistor, 4.7 KOhm, +/- 1%, 0.1 W, -55 to 155 degC, 0402 (1005 Metric), RoHS, Tape and Reel"
"R108","4.7K_0402","TopLayer","RESC1005X40X25LL05T05","677.165","-1137.795","0","Chip Resistor, 4.7 KOhm, +/- 1%, 0.1 W, -55 to 155 degC, 0402 (1005 Metric), RoHS, Tape and Reel"
"R107","DNI_49.9_1%_0402","TopLayer","RESC1005X40X25LL05T10","2598.425","-1204.724","270",""
"R106","DNI_49.9_1%_0402","TopLayer","RESC1005X40X25LL05T10","2578.740","-1047.244","180",""
"R105","DNI_49.9_1%_0402","TopLayer","RESC1005X40X25LL05T10","2389.764","-1224.409","180",""
"R104","DNI_49.9_1%_0402","TopLayer","RESC1005X40X25LL05T10","2350.394","-1153.543","90",""
"R103","DNI_27_1%_0402","TopLayer","RESC1005X40X25NL05T05","5757.874","-1062.992","0",""
"R102","DNI_27_1%_0402","TopLayer","RESC1005X40X25NL05T05","5834.646","-807.087","0",""
"R101","DNI_27_1%_0402","TopLayer","RESC1005X40X25NL05T05","6062.992","-1011.811","0",""
"R100","DNI_27_1%_0402","TopLayer","RESC1005X40X25NL05T05","6100.394","-818.898","0",""
"U23","TMUX1072RUTR","TopLayer","FP-RUT0012A-MFG","2484.252","-1212.598","90","IC SWITCH SPDT DUAL 12UQFN"
"U22","TMUX1072RUTR","TopLayer","FP-RUT0012A-MFG","5842.520","-933.071","0","IC SWITCH SPDT DUAL 12UQFN"
"U21","TMUX1072RUTR","TopLayer","FP-RUT0012A-MFG","6171.260","-933.071","0","IC SWITCH SPDT DUAL 12UQFN"
"U20","FT234XD-R","TopLayer","FP-DFN-12-IPC_B","6854.331","-531.496","90","IC USB SERIAL BASIC UART 12DFN"
"SW1","A6H-2102","TopLayer","FP-A6H-2102-MFG","4236.221","-1248.032","0","SWITCH SLIDE DIP SPST 25MA 24V"
"R99","49.9_1%_0402","TopLayer","RESC1005X40X25LL05T10","2539.370","-1307.087","180",""
"R98","49.9_1%_0402","TopLayer","RESC1005X40X25LL05T10","2555.118","-1153.543","180",""
"R97","49.9_1%_0402","TopLayer","RESC1005X40X25LL05T10","2440.945","-1307.087","0",""
"R96","49.9_1%_0402","TopLayer","RESC1005X40X25LL05T10","2440.945","-1141.732","0",""
"R95","200_1%_0402","TopLayer","FP-ERJ2RK-IPC_A","4097.301","-1177.867","270","RES SMD 200 OHM 1% 1/10W 0402"
"R94","200_1%_0402","TopLayer","FP-ERJ2RK-IPC_A","4366.142","-1188.892","270","RES SMD 200 OHM 1% 1/10W 0402"
"R93","27_1%_0402","TopLayer","RESC1005X40X25NL05T05","5736.221","-1003.937","0",""
"R92","27_1%_0402","TopLayer","RESC1005X40X25NL05T05","5944.882","-980.315","180",""
"R91","27_1%_0402","TopLayer","RESC1005X40X25NL05T05","5740.158","-881.890","0",""
"R90","27_1%_0402","TopLayer","RESC1005X40X25NL05T05","5940.945","-850.394","270",""
"R89","10K_1%_0402","TopLayer","RESC1005X40X25LL05T10","4381.890","-1110.236","180",""
"R88","10K_1%_0402","TopLayer","RESC1005X40X25LL05T10","4081.693","-1106.299","0",""
"R87","27_1%_0402","TopLayer","RESC1005X40X25NL05T05","6066.929","-952.756","0",""
"R86","27_1%_0402","TopLayer","RESC1005X40X25NL05T05","6279.528","-996.063","180",""
"R85","27_1%_0402","TopLayer","RESC1005X40X25NL05T05","6066.929","-897.638","0",""
"R84","27_1%_0402","TopLayer","RESC1005X40X25NL05T05","6275.591","-866.142","180",""
"R83","15K_1%_0402","TopLayer","FP-ERJ2R-MFG","6858.268","-275.591","270","RES SMD 15K OHM 1% 1/10W 0402"
"R82","10K_1%_0402","TopLayer","RESC1005X40X25LL05T10","6791.339","-688.976","0",""
"R81","27_1%_0402","TopLayer","RESC1005X40X25NL05T05","6712.598","-811.024","90",""
"J43","2049261103","TopLayer","FP-2049261103-MFG","6884.842","-889.764","90","CONN RCPT USB2.0 MICRO B SMD R/A"
"FB1","600ohm_1.3A_0603","TopLayer","FP-BLM18-0_15-t0_8-IPC_A","6724.409","-1039.370","270","Chip Ferrite Bead, 0603, 600O @ 100MHz, 0.15O, 25%, 1.3A"
"D25","SML-LX0603IW-TR","TopLayer","FP-SML-LX0603IW-TR-MFG","4098.425","-1299.213","270","LED RED DIFFUSED SMD"
"D24","SML-LX0603IW-TR","TopLayer","FP-SML-LX0603IW-TR-MFG","4366.142","-1295.276","270","LED RED DIFFUSED SMD"
"C96","0.1uF_25V_0402","TopLayer","FP-0402-L_1_0_1-W_0_5_0_1-IPC_C","2503.937","-1106.299","90","General Purpose Ceramic Capacitor, 0402, 100nF, 10%, X7R, 15%, 25V"
"C95","0.1uF_25V_0402","TopLayer","FP-0402-L_1_0_1-W_0_5_0_1-IPC_C","5972.441","-921.260","90","General Purpose Ceramic Capacitor, 0402, 100nF, 10%, X7R, 15%, 25V"
"C94","0.1uF_25V_0402","TopLayer","FP-0402-L_1_0_1-W_0_5_0_1-IPC_C","6275.591","-933.071","0","General Purpose Ceramic Capacitor, 0402, 100nF, 10%, X7R, 15%, 25V"
"C93","0.1uF_25V_0402","TopLayer","FP-0402-L_1_0_1-W_0_5_0_1-IPC_C","6866.142","-377.953","90","General Purpose Ceramic Capacitor, 0402, 100nF, 10%, X7R, 15%, 25V"
"C92","0.1uF_25V_0402","TopLayer","FP-0402-L_1_0_1-W_0_5_0_1-IPC_C","6940.945","-379.310","90","General Purpose Ceramic Capacitor, 0402, 100nF, 10%, X7R, 15%, 25V"
"C91","10nF_50V_0402","TopLayer","FP-CC0402-MFG","6795.276","-318.898","90","CAP CER 10000PF 50V X7R 0402"
"C90","4.7uF_16V_0402","TopLayer","FP-CL829-IPC_C","6641.732","-1106.299","180","Cap Ceramic 4.7uF 16V X5R ±20% SMD 0402 +85°C Paper T/R"
"C89","0.1uF_25V_0402","TopLayer","FP-0402-L_1_0_1-W_0_5_0_1-IPC_C","6937.008","-661.417","0","General Purpose Ceramic Capacitor, 0402, 100nF, 10%, X7R, 15%, 25V"
"C88","47pF_50V_0402","TopLayer","CAPC1005X55X25LL05T10","6625.984","-811.024","270",""
"C87","47pF_50V_0402","TopLayer","CAPC1005X55X25LL05T10","6755.905","-783.465","270",""
"C86","10nF_50V_0402","TopLayer","FP-CC0402-MFG","6696.850","-944.882","180","CAP CER 10000PF 50V X7R 0402"
"D23","SMDJ12A","TopLayer","FP-DO-214AB_SMC_J-Bend-MFG","5649.606","-1692.913","180","TVS DIODE 12V 19.9V DO214AB"
"R77","200_1%_0402","TopLayer","FP-ERJ2RK-IPC_A","6862.205","-3157.480","180","RES SMD 200 OHM 1% 1/10W 0402"
"D20","SML-LX0603IW-TR","TopLayer","FP-SML-LX0603IW-TR-MFG","6728.346","-3157.480","180","LED RED DIFFUSED SMD"
"D22","SD103AWS-7-F","TopLayer","FP-SOD323-MFG","6196.850","-2960.630","0","DIODE SCHOTTKY 40V 350MA SOD323"
"D21","SD103AWS-7-F","TopLayer","FP-SOD323-MFG","6307.087","-2338.583","0","DIODE SCHOTTKY 40V 350MA SOD323"
"U19","INA219BIDR","TopLayer","FP-D0008A-MFG","6614.173","-3000.000","180","IC MONITOR PWR/CURR BIDIR 8-SOIC"
"U18","MIC24052YJL-TR","TopLayer","QFN28_5X6_MCH","5736.221","-2720.472","90","No Description Available"
"U17","INA219BIDR","TopLayer","FP-D0008A-MFG","6692.913","-2283.465","180","IC MONITOR PWR/CURR BIDIR 8-SOIC"
"R80","0_1%_0402","TopLayer","RESC1005X40X25LL05T05","6822.834","-3062.992","0","Chip Resistor, 0 Ohm, 0.1 W, -55 to 155 degC, 0402 (1005 Metric), RoHS, Tape and Reel"
"R79","0_1%_0402","TopLayer","RESC1005X40X25LL05T05","6822.834","-3019.685","0","Chip Resistor, 0 Ohm, 0.1 W, -55 to 155 degC, 0402 (1005 Metric), RoHS, Tape and Reel"
"R78","787_1%_0402","TopLayer","RESC1005X40X25NL10T10","5501.969","-2659.449","0",""
"R76","2.49K_1%_0402","TopLayer","RESC1005X40X25NL05T10","5529.528","-2596.457","90",""
"R75","19.6K_1%_0402","TopLayer","RESC1005X40X25NL05T10","5834.646","-2854.331","0",""
"R74","2.21_1%_0402","TopLayer","RESC1005X40X25ML05T10","5500.984","-2850.394","0",""
"R73","1.21_1%_0402","TopLayer","RESC1005X40X25LL10T10","5940.945","-2838.583","90",""
"R72","2mOhm_1%_1206","TopLayer","RESC3216X89X64NL25T25","6393.701","-2692.913","0",""
"R71","2.21_1%_0402","TopLayer","RESC1005X40X25ML05T10","5834.646","-2897.638","0",""
"R70","1.21_1%_0402","TopLayer","RESC0402(1005)_N","5606.299","-2866.142","0","1R21 0.063W 1% 0402 (1005 Metric)  SMD"
"R69","1.21_1%_0402","TopLayer","RESC0402(1005)_N","6078.740","-2952.756","270","1R21 0.063W 1% 0402 (1005 Metric)  SMD"
"R68","4.7K_0402","TopLayer","RESC1005X40X25LL05T05","5503.937","-2708.661","0","Chip Resistor, 4.7 KOhm, +/- 1%, 0.1 W, -55 to 155 degC, 0402 (1005 Metric), RoHS, Tape and Reel"
"R67","4.7K_0402","TopLayer","RESC1005X40X25LL05T05","5503.937","-2748.032","0","Chip Resistor, 4.7 KOhm, +/- 1%, 0.1 W, -55 to 155 degC, 0402 (1005 Metric), RoHS, Tape and Reel"
"R66","0_1%_0402","TopLayer","RESC1005X40X25LL05T05","6736.220","-2421.260","180","Chip Resistor, 0 Ohm, 0.1 W, -55 to 155 degC, 0402 (1005 Metric), RoHS, Tape and Reel"
"R65","0_1%_0402","TopLayer","RESC1005X40X25LL05T05","6677.165","-2437.008","270","Chip Resistor, 0 Ohm, 0.1 W, -55 to 155 degC, 0402 (1005 Metric), RoHS, Tape and Reel"
"R64","0_1%_0402","TopLayer","RESC1005X40X25LL05T05","5641.732","-1094.488","0","Chip Resistor, 0 Ohm, 0.1 W, -55 to 155 degC, 0402 (1005 Metric), RoHS, Tape and Reel"
"R63","470_1%_0402","TopLayer","RESC1005X40X25ML05T10","5519.685","-2003.937","0",""
"R62","0_1%_0402","TopLayer","RESC1005X40X25LL05T05","5519.685","-1090.551","180","Chip Resistor, 0 Ohm, 0.1 W, -55 to 155 degC, 0402 (1005 Metric), RoHS, Tape and Reel"
"R61","2.49K_1%_0402","TopLayer","RESC1005X40X25NL05T10","5661.417","-1996.063","90",""
"R60","19.6K_1%_0402","TopLayer","RESC1005X40X25NL05T10","5992.126","-2299.213","90",""
"R59","2.21_1%_0402","TopLayer","RESC1005X40X25ML05T10","5547.244","-2133.858","270",""
"C85","10uF_16V_0603","TopLayer","FP-0603-L_1_6_0_2-W_0_8_0-MFG","6433.071","-2948.819","270","Multilayer Ceramic Capacitor 10uF 16V X5R 20% SMD 0603 T/R"
"C84","0.1uF_0402","TopLayer","CAPC1005X56X25NL10T15","6645.669","-2830.709","180",""
"C83","0.1uF_25V_0402","TopLayer","FP-0402-L_1_0_1-W_0_5_0_1-IPC_C","6417.323","-2779.528","180","General Purpose Ceramic Capacitor, 0402, 100nF, 10%, X7R, 15%, 25V"
"C82","1uF_16V_0402","TopLayer","FP-0402-L_1_0_0_05-W_0_5-IPC_A","6645.669","-2763.780","0","None"
"C81","2.2uF_16V_0402","TopLayer","FP-C1005-050-0_05-IPC_A","6653.800","-2523.028","0","Multilayer Ceramic Capacitors 2.2µF ±10% 16V X5R SMD 0402"
"C80","10uF_16V_0603","TopLayer","FP-0603-L_1_6_0_2-W_0_8_0-MFG","6653.543","-2602.362","0","Multilayer Ceramic Capacitor 10uF 16V X5R 20% SMD 0603 T/R"
"C79","100uF_16V_2917","TopLayer","FP-T495D107K016ATE125-MFG","6433.071","-2543.307","0","CAP TANT 100UF 10% 16V 2917"
"C78","47uF_16V_1206","TopLayer","FP-C3216-160-0_2-MFG","6641.732","-2685.039","0","Multilayer Ceramic Capacitors 47uF ±20% 16V X5R SMD 1206"
"C77","4.7uF_50V_1206","TopLayer","FP-GRM31C-0_2-e0_3_0_8-IPC_C","5944.882","-2535.433","90","Chip Multilayer Ceramic Capacitors for General Purpose, 1206, 4.7uF, X7R, 15%, 10%, 50V"
"C76","4.7uF_50V_1206","TopLayer","FP-GRM31C-0_2-e0_3_0_8-IPC_C","6055.118","-2539.370","90","Chip Multilayer Ceramic Capacitors for General Purpose, 1206, 4.7uF, X7R, 15%, 10%, 50V"
"C75","100uF_16V_2917","TopLayer","FP-T495D107K016ATE125-MFG","5653.543","-2448.819","0","CAP TANT 100UF 10% 16V 2917"
"C74","0.1uF_50V_0603","TopLayer","FP-CC0603-DA-MFG","5724.409","-2917.323","180","CAP CER 0.1UF 50V X7R 0603"
"C73","4.7nF_50V_0402","TopLayer","FP-CC0402-MFG","5478.346","-2596.457","270","CAP CER 4700PF 50V X7R 0402"
"C72","DNI_1nF_50V_0402","TopLayer","FP-CL180-IPC_C","5917.323","-2913.386","270","Cap Ceramic 1nF 50V C0G ±5% SMD 0402 +125°C Paper T/R"
"C71","0.1uF_25V_0402","TopLayer","FP-0402-L_1_0_1-W_0_5_0_1-IPC_C","5500.000","-2799.213","180","General Purpose Ceramic Capacitor, 0402, 100nF, 10%, X7R, 15%, 25V"
"C70","2.2uF_16V_0402","TopLayer","FP-C1005-050-0_05-IPC_A","5599.741","-2925.197","180","Multilayer Ceramic Capacitors 2.2µF ±10% 16V X5R SMD 0402"
"C69","1uF_16V_0402","TopLayer","FP-0402-L_1_0_0_05-W_0_5-IPC_A","5500.000","-2917.323","180","None"
"C68","0.1uF_50V_0603","TopLayer","FP-CC0603-DA-MFG","6003.937","-2956.693","180","CAP CER 0.1UF 50V X7R 0603"
"R58","4.7K_0402","TopLayer","RESC1005X40X25LL05T05","5047.244","-1114.173","270","Chip Resistor, 4.7 KOhm, +/- 1%, 0.1 W, -55 to 155 degC, 0402 (1005 Metric), RoHS, Tape and Reel"
"R57","4.7K_0402","TopLayer","RESC1005X40X25LL05T05","5086.614","-1114.173","270","Chip Resistor, 4.7 KOhm, +/- 1%, 0.1 W, -55 to 155 degC, 0402 (1005 Metric), RoHS, Tape and Reel"
"R56","DNI_4.7K_0402","TopLayer","RESC1005X40X25LL05T05","4736.221","-1220.472","90","Chip Resistor, 4.7 KOhm, +/- 1%, 0.1 W, -55 to 155 degC, 0402 (1005 Metric), RoHS, Tape and Reel"
"R55","4.7K_0402","TopLayer","RESC1005X40X25LL05T05","4917.323","-1090.551","180","Chip Resistor, 4.7 KOhm, +/- 1%, 0.1 W, -55 to 155 degC, 0402 (1005 Metric), RoHS, Tape and Reel"
"R54","0_1%_0402","TopLayer","RESC1005X40X25LL05T05","4783.465","-1090.551","0","Chip Resistor, 0 Ohm, 0.1 W, -55 to 155 degC, 0402 (1005 Metric), RoHS, Tape and Reel"
"R53","4.7K_0402","TopLayer","RESC1005X40X25LL05T05","4720.472","-1169.291","180","Chip Resistor, 4.7 KOhm, +/- 1%, 0.1 W, -55 to 155 degC, 0402 (1005 Metric), RoHS, Tape and Reel"
"R52","4.7K_0402","TopLayer","RESC1005X40X25LL05T05","4850.394","-1090.551","180","Chip Resistor, 4.7 KOhm, +/- 1%, 0.1 W, -55 to 155 degC, 0402 (1005 Metric), RoHS, Tape and Reel"
"R51","4.7K_0402","TopLayer","RESC1005X40X25LL05T05","5043.307","-1196.850","180","Chip Resistor, 4.7 KOhm, +/- 1%, 0.1 W, -55 to 155 degC, 0402 (1005 Metric), RoHS, Tape and Reel"
"R50","4.7K_0402","TopLayer","RESC1005X40X25LL05T05","4744.095","-1346.457","0","Chip Resistor, 4.7 KOhm, +/- 1%, 0.1 W, -55 to 155 degC, 0402 (1005 Metric), RoHS, Tape and Reel"
"C67","0.1uF_0402","TopLayer","CAPC1005X56X25NL10T15","5027.559","-1255.906","90",""
"C66","0.1uF_0402","TopLayer","CAPC1005X56X25NL10T15","5039.370","-1334.646","180",""
"C65","1uF_0402","TopLayer","FP-0402-L_1_0_0_05-W_0_5-IPC_C","4988.189","-1098.425","0","None"
"C64","0.1uF","TopLayer","CAPC1608X87X45ML20T05","6681.102","-472.441","180","C0603X104K5RACAUTO"
"C57","0.1uF","TopLayer","CAPC1608X87X45ML20T05","6055.118","-448.819","0","C0603X104K5RACAUTO"
"C56","10uF","TopLayer","FP-MK212BG-MFG","6677.165","-566.929","0","None"
"C55","10uF","TopLayer","FP-MK212BG-MFG","6055.118","-539.370","180","None"
"C54","0.1uF","TopLayer","CAPC1608X87X45ML20T05","559.055","-397.638","270","C0603X104K5RACAUTO"
"C43","0.1uF","TopLayer","CAPC1608X87X45ML20T05","1114.173","-405.512","270","C0603X104K5RACAUTO"
"C42","10uF","TopLayer","FP-MK212BG-MFG","472.441","-393.701","90","None"
"C41","10uF","TopLayer","FP-MK212BG-MFG","1244.094","-409.449","90","None"
"R49","0_1%_0402","TopLayer","RESC1005X40X25LL05T05","4248.032","-1838.583","0","Chip Resistor, 0 Ohm, 0.1 W, -55 to 155 degC, 0402 (1005 Metric), RoHS, Tape and Reel"
"R48","0_1%_0402","TopLayer","RESC1005X40X25LL05T05","1401.575","-1295.276","270","Chip Resistor, 0 Ohm, 0.1 W, -55 to 155 degC, 0402 (1005 Metric), RoHS, Tape and Reel"
"SKT10","0332-0-43-80-18-27-10-0","TopLayer","SolderSocket","2464.724","-3271.653","90","Solder socket for pin headers"
"SKT9","0332-0-43-80-18-27-10-0","TopLayer","SolderSocket","3023.622","-3165.354","90","Solder socket for pin headers"
"SKT8","0332-0-43-80-18-27-10-0","TopLayer","SolderSocket","2584.724","-3271.653","90","Solder socket for pin headers"
"SKT7","0332-0-43-80-18-27-10-0","TopLayer","SolderSocket","3023.622","-1566.929","90","Solder socket for pin headers"
"SKT6","0332-0-43-80-18-27-10-0","TopLayer","SolderSocket","1425.197","-2366.142","90","Solder socket for pin headers"
"SKT5","0332-0-43-80-18-27-10-0","TopLayer","SolderSocket","1425.197","-3165.354","90","Solder socket for pin headers"
"SKT4","0332-0-43-80-18-27-10-0","TopLayer","SolderSocket","2940.945","-3271.653","90","Solder socket for pin headers"
"SKT3","0332-0-43-80-18-27-10-0","TopLayer","SolderSocket","2822.835","-3271.653","90","Solder socket for pin headers"
"SKT2","0332-0-43-80-18-27-10-0","TopLayer","SolderSocket","1425.197","-1566.929","90","Solder socket for pin headers"
"SKT1","0332-0-43-80-18-27-10-0","TopLayer","SolderSocket","2704.724","-3271.653","90","Solder socket for pin headers"
"P1","TSW-105-05-L-S","TopLayer","SMTC-TSW-105-05-X-S","1614.961","-1200.787","180","0.025" SQ Post Header, Through-hole, Vertical, -55 to 125 degC, 2.54 mm Pitch, 5-Pin, Male, RoHS"
"R47","DNI_0_5%_1206","TopLayer","RESC3116X65X50ML20T20","3653.000","-1362.205","0",""
"J38","39-30-0040","TopLayer","FP-39-30-0040-MFG","6472.008","-1356.949","90","CONN HEADER R/A 4POS 4.2MM"
"R46","DNI_0_5%_1206","TopLayer","RESC3116X65X50ML20T20","3653.000","-1125.984","0",""
"R45","0_5%_1206","TopLayer","RESC3116X65X50ML20T20","3653.000","-1248.032","0",""
"R44","DNI_0_5%_1206","TopLayer","RESC3116X65X50ML20T20","5952.756","-1677.165","180",""
"D19","STPS5L60S","TopLayer","FP-STPS5L60S-MFG","6251.968","-1685.039","0","DIODE SCHOTTKY 60V 5A SMC"
"D12","STPS5L60S","TopLayer","FP-STPS5L60S-MFG","5960.630","-1342.520","90","DIODE SCHOTTKY 60V 5A SMC"
"J37","Single FPGA Conn","TopLayer","SingleFPGAConn","4309.097","-3085.975","90",""
"J36","Single FPGA Conn","TopLayer","SingleFPGAConn","3409.043","-2340.449","0",""
"J35","Single FPGA Conn","TopLayer","SingleFPGAConn","4309.097","-1604.766","270",""
"J34","Single FPGA Conn","TopLayer","SingleFPGAConn","5283.953","-2340.449","180",""
"J31","SA53_Header","TopLayer","SA53_Header","3013.188","-2365.934","180",""
"J13","GNSS Header 16-pin","TopLayer","GNSS_Header_16-pin","6406.398","-415.843","180",""
"J6","GNSS Header 16-pin","TopLayer","GNSS_Header_16-pin","827.855","-461.118","0",""
"R43","27_1%_0402","TopLayer","RESC1005X40X25NL05T05","6677.165","-811.024","90",""
"R42","27_1%_0402","TopLayer","RESC1005X40X25NL05T05","6803.150","-413.386","180",""
"D10","BLUE","TopLayer","FP-LTST-C191TBKT-MFG","403.543","118.110","90","LED BLUE CLEAR CHIP SMD"
"D9","BLUE","TopLayer","FP-LTST-C191TBKT-MFG","334.646","118.110","90","LED BLUE CLEAR CHIP SMD"
"D3","BLUE","TopLayer","FP-LTST-C191TBKT-MFG","265.748","118.110","90","LED BLUE CLEAR CHIP SMD"
"U16","NC7WV125K8X","TopLayer","SOP50P310X90-8N","748.032","-3188.976","180","Integrated Circuit"
"U12","NC7WV125K8X","TopLayer","SOP50P310X90-8N","757.874","-2125.984","180","Integrated Circuit"
"U11","NC7WV125K8X","TopLayer","SOP50P310X90-8N","757.874","-2647.638","180","Integrated Circuit"
"U8","NC7WV125K8X","TopLayer","SOP50P310X90-8N","748.032","-1594.488","180","Integrated Circuit"
"U6","IS32FL3207","TopLayer","IS32FL3207","1033.465","-1259.842","0",""
"R41","4.7K","TopLayer","RESC1608X55X30NL15T15","797.244","-1358.268","0","Precision Thick Film Chip Resistor, 4.7 KOhm, +/- 1%, -55 to 155 degC, 0603 (1608 Metric), RoHS, Tape and Reel ERJ-3EKF4701V"
"R40","DNI_100k","TopLayer","FP-RC0603-0_55-MFG","799.213","-1102.362","0","RES SMD 100K OHM 1% 1/10W 0603"
"R39","200 OHM","TopLayer","RESC1608X55X30NL15T15","472.441","-19.685","90","ERJ-3EKF2000V"
"R38","200 OHM","TopLayer","RESC1608X55X30NL15T15","403.543","-19.685","90","ERJ-3EKF2000V"
"R36","200 OHM","TopLayer","RESC1608X55X30NL15T15","334.646","-19.685","90","ERJ-3EKF2000V"
"R35","200 OHM","TopLayer","RESC1608X55X30NL15T15","265.748","-19.685","90","ERJ-3EKF2000V"
"R34","49.9R","TopLayer","RESC1608X55X25NL10T15","568.898","-3169.291","180","General Purpose Chip Resistor, 49.9 Ohm, +/- 1%, -55 to 155 degC, 0603 (1608 Metric), RoHS, Tape and Reel"
"R33","49.9R","TopLayer","RESC1608X55X25NL10T15","580.709","-2106.299","180","General Purpose Chip Resistor, 49.9 Ohm, +/- 1%, -55 to 155 degC, 0603 (1608 Metric), RoHS, Tape and Reel"
"R32","4.7K","TopLayer","RESC1608X55X30NL15T15","748.032","-3326.772","270","Precision Thick Film Chip Resistor, 4.7 KOhm, +/- 1%, -55 to 155 degC, 0603 (1608 Metric), RoHS, Tape and Reel ERJ-3EKF4701V"
"R31","4.7K","TopLayer","RESC1608X55X30NL15T15","826.772","-3326.772","270","Precision Thick Film Chip Resistor, 4.7 KOhm, +/- 1%, -55 to 155 degC, 0603 (1608 Metric), RoHS, Tape and Reel ERJ-3EKF4701V"
"P3","EXT GPIO","TopLayer","HDR2X6_CEN","5640.551","89.370","180","Header, 6-Pin, Dual row"
"J4","1909763-1","TopLayer","TECO-1909763-1_V","412.894","-3169.291","270","Ultra Miniature Coaxial Connector Jack, 60 V, 50 Ohm, -40 to 90 degC, RoHS, Tape and Reel"
"J2","1909763-1","TopLayer","TECO-1909763-1_V","412.894","-2106.299","270","Ultra Miniature Coaxial Connector Jack, 60 V, 50 Ohm, -40 to 90 degC, RoHS, Tape and Reel"
"J3","1909763-1","TopLayer","TECO-1909763-1_V","412.894","-2627.953","270","Ultra Miniature Coaxial Connector Jack, 60 V, 50 Ohm, -40 to 90 degC, RoHS, Tape and Reel"
"J1","1909763-1","TopLayer","TECO-1909763-1_V","412.894","-1574.803","270","Ultra Miniature Coaxial Connector Jack, 60 V, 50 Ohm, -40 to 90 degC, RoHS, Tape and Reel"
"D18","155124M173200","TopLayer","155124M173200","-190.453","-3413.386","90","LED (Multiple)"
"D17","155124M173200","TopLayer","155124M173200","-190.453","-2885.827","90","LED (Multiple)"
"D16","155124M173200","TopLayer","155124M173200","-190.453","-2350.394","90","LED (Multiple)"
"D15","155124M173200","TopLayer","155124M173200","-190.453","-1822.835","90","LED (Multiple)"
"C40","0.1uF","TopLayer","CAPC1608X87X45ML20T05","826.772","-1259.843","90","C0603X104K5RACAUTO"
"C38","1uF","TopLayer","FP-C0603C105K3PACTU-MFG","757.874","-1253.937","270","CAP CER 1UF 25V X5R 0603"
"C33","0.1uF_0402","TopLayer","CAPC1005X56X25NL10T15","4980.315","-1413.386","180",""
"C32","0.1uF_0402","TopLayer","CAPC1005X56X25NL10T15","4980.315","-1374.016","180",""
"R37","10K","TopLayer","RESC1608X55X30LL15T20","4586.614","-1376.472","180","Chip Resistor, 10 KOhm, +/- 1%, 0.1 W, -55 to 155 degC, 0603 (1608 Metric), RoHS, Tape and Reel RMCF0603FT10K0"
"U15","RCB-F9T-1","TopLayer","GNSS","6406.398","-258.362","180","MOD, GPS"
"C37","0.1uF","TopLayer","CAPC1608X87X45ML20T05","6688.976","-161.417","180","C0603X104K5RACAUTO"
"C36","0.1uF","TopLayer","CAPC1608X87X45ML20T05","6127.664","-140.170","0","C0603X104K5RACAUTO"
"C35","10uF","TopLayer","FP-MK212BG-MFG","6696.850","-236.220","0","None"
"C34","10uF","TopLayer","FP-MK212BG-MFG","6131.890","-215.055","180","None"
"D2","8240136","TopLayer","SOT143-4L","344.488","-2874.016","90","TVS Diode WE-TVS-HS, VRWM=3.3V"
"D1","8240136","TopLayer","SOT143-4L","344.488","-1797.244","90","TVS Diode WE-TVS-HS, VRWM=3.3V"
"R27","4.7K","TopLayer","RESC1608X55X30NL15T15","1665.354","-1094.488","0","Precision Thick Film Chip Resistor, 4.7 KOhm, +/- 1%, -55 to 155 degC, 0603 (1608 Metric), RoHS, Tape and Reel ERJ-3EKF4701V"
"R26","4.7K","TopLayer","RESC1608X55X30NL15T15","1515.748","-1094.488","0","Precision Thick Film Chip Resistor, 4.7 KOhm, +/- 1%, -55 to 155 degC, 0603 (1608 Metric), RoHS, Tape and Reel ERJ-3EKF4701V"
"U10","MAC-SA5X","TopLayer","SA53","2258.562","-2399.291","180","MOD, MAC, MAC-SA5X, ATOMIC CLOCK"
"R14","4.7K","TopLayer","RESC1608X55X30NL15T15","826.772","-1722.441","270","Precision Thick Film Chip Resistor, 4.7 KOhm, +/- 1%, -55 to 155 degC, 0603 (1608 Metric), RoHS, Tape and Reel ERJ-3EKF4701V"
"U14","BME280","TopLayer","FP-BME280-MFG","5157.480","-1248.520","0","SENSOR PRESSURE HUMIDITY TEMP"
"U13","BNO055","TopLayer","FP-BNO055-MFG","4889.764","-1224.409","270","IMU ACCEL/GYRO/MAG I2C 28LGA"
"U4","DS90LV028AQMA","TopLayer","M08A_L","2185.039","-1218.992","0","Automotive LVDS Dual Differential Line Receiver, 8-pin Narrow SOIC"
"U3","DS90LV027AQMA","TopLayer","M08A_N","2889.764","-1214.465","0","Automotive LVDS Dual Differential Driver, 8-pin Narrow SOIC"
"R25","49.9R","TopLayer","RESC1608X55X25NL10T15","570.866","-1574.803","180","General Purpose Chip Resistor, 49.9 Ohm, +/- 1%, -55 to 155 degC, 0603 (1608 Metric), RoHS, Tape and Reel"
"R17","4.7K","TopLayer","RESC1608X55X30NL15T15","757.874","-2785.433","270","Precision Thick Film Chip Resistor, 4.7 KOhm, +/- 1%, -55 to 155 degC, 0603 (1608 Metric), RoHS, Tape and Reel ERJ-3EKF4701V"
"R13","27_1%_0402","TopLayer","RESC1005X40X25NL05T05","6964.567","-464.567","270",""
"R12","110R","TopLayer","RESC1609X50X30NL10T20","1998.032","-1169.780","270",""
"R11","4.7K","TopLayer","RESC1608X55X25LL10T15","2669.291","-1291.339","0","Chip Resistor, 4.7 KOhm, +/- 1%, 0.1 W, -55 to 155 degC, 0603 (1608 Metric), RoHS, Tape and Reel RC0603FR-074K7L"
"R10","4.7K","TopLayer","RESC1608X55X25LL10T15","2690.945","-1188.976","0","Chip Resistor, 4.7 KOhm, +/- 1%, 0.1 W, -55 to 155 degC, 0603 (1608 Metric), RoHS, Tape and Reel RC0603FR-074K7L"
"C31","0.1uF","TopLayer","CAPC1608X87X45ML20T05","5285.433","-1148.126","270","C0603X104K5RACAUTO"
"C30","0.1uF","TopLayer","CAPC1608X87X45ML20T05","5159.449","-1120.567","180","C0603X104K5RACAUTO"
"C29","0.1uF","TopLayer","CAPC1608X87X45ML20T05","679.134","-3326.772","270","C0603X104K5RACAUTO"
"C28","0.1uF","TopLayer","CAPC1608X87X45ML20T05","688.976","-2244.094","270","C0603X104K5RACAUTO"
"C27","0.1uF","TopLayer","CAPC1608X87X45ML20T05","688.976","-2785.433","270","C0603X104K5RACAUTO"
"C26","0.1uF","TopLayer","CAPC1608X87X45ML20T05","679.134","-1722.441","270","C0603X104K5RACAUTO"
"C24","0.1uF","TopLayer","CAPC1608X87X45ML20T05","2370.079","-1082.677","0","C0603X104K5RACAUTO"
"C23","0.1uF","TopLayer","CAPC1608X87X45ML20T05","2667.323","-1120.567","0","C0603X104K5RACAUTO"
"AN1","RF2-49B-T-00-50-G-HDW","TopLayer","AMPH-901-143-6RFX_V","-84.645","-1573.323","180","Coaxial connector, 50 Ohm, -65 to 165 degC, 5-Pin THD, RoHS, Bulk"
"AN3","RF2-49B-T-00-50-G-HDW","TopLayer","AMPH-901-143-6RFX_V","-84.646","-2636.299","180","Coaxial connector, 50 Ohm, -65 to 165 degC, 5-Pin THD, RoHS, Bulk"
"AN2","RF2-49B-T-00-50-G-HDW","TopLayer","AMPH-901-143-6RFX_V","-84.646","-2104.803","180","Coaxial connector, 50 Ohm, -65 to 165 degC, 5-Pin THD, RoHS, Bulk"
"AN4","RF2-49B-T-00-50-G-HDW","TopLayer","AMPH-901-143-6RFX_V","-84.645","-3167.811","180","Coaxial connector, 50 Ohm, -65 to 165 degC, 5-Pin THD, RoHS, Bulk"
"U7","AT24MAC402-STUM-T","TopLayer","FP-5TS1-IPC_C","4606.299","-1258.362","270","IC EEPROM 2K I2C 1MHZ SOT23-5"
"C25","0.1uF","TopLayer","CAPC1608X87X45ML20T05","4478.346","-1258.362","270","C0603X104K5RACAUTO"
"R16","4.7K","TopLayer","RESC1608X55X30NL15T15","836.614","-2785.433","270","Precision Thick Film Chip Resistor, 4.7 KOhm, +/- 1%, -55 to 155 degC, 0603 (1608 Metric), RoHS, Tape and Reel ERJ-3EKF4701V"
"R15","4.7K","TopLayer","RESC1608X55X30NL15T15","748.032","-1722.441","270","Precision Thick Film Chip Resistor, 4.7 KOhm, +/- 1%, -55 to 155 degC, 0603 (1608 Metric), RoHS, Tape and Reel ERJ-3EKF4701V"
"R5","1.21_1%_0402","TopLayer","RESC0402(1005)_N","5677.166","-2220.472","270","1R21 0.063W 1% 0402 (1005 Metric)  SMD"
"U9","RCB-F9T","TopLayer","GNSS","827.855","-618.598","0","MOD, GPS"
"U5","HTST-105-01-L-DV-A","TopLayer","SAMTEC_HTST-105-01-L-DV-A","5892.913","-3300.394","0","CONN, HDR, 2X5, VERT, 0.1IN  SHROUDED, SMT, HTSH SERIES"
"U2","INA219BIDR","TopLayer","FP-D0008A-MFG","5511.811","-1263.780","270","IC MONITOR PWR/CURR BIDIR 8-SOIC"
"U1","MIC24052YJL-TR","TopLayer","QFN28_5X6_MCH","5847.964","-2134.404","90","No Description Available"
"R30","4.7K","TopLayer","RESC1608X55X30NL15T15","757.874","-2244.094","270","Precision Thick Film Chip Resistor, 4.7 KOhm, +/- 1%, -55 to 155 degC, 0603 (1608 Metric), RoHS, Tape and Reel ERJ-3EKF4701V"
"R29","4.7K","TopLayer","RESC1608X55X30NL15T15","826.772","-2244.095","270","Precision Thick Film Chip Resistor, 4.7 KOhm, +/- 1%, -55 to 155 degC, 0603 (1608 Metric), RoHS, Tape and Reel ERJ-3EKF4701V"
"R28","49.9R","TopLayer","RESC1608X55X25NL10T15","580.709","-2627.953","180","General Purpose Chip Resistor, 49.9 Ohm, +/- 1%, -55 to 155 degC, 0603 (1608 Metric), RoHS, Tape and Reel"
"R24","ERJ-2GE0R00X","TopLayer","RESC1005X04N","1330.709","-3472.441","0","RES, 0. OHM, 1%, 1/16W, TF, AEC-Q200, 0402"
"R23","ERJ-2GE0R00X","TopLayer","RESC1005X04N","1330.709","-3429.134","0","RES, 0. OHM, 1%, 1/16W, TF, AEC-Q200, 0402"
"R22","ERJ-3EKF4701V","TopLayer","RESC1608X50N","1134.252","-2636.315","180","RES, 4.7K, 1%, 1/10W, TF, 0603"
"R21","CRCW080533R0FKEA","TopLayer","RESC2012X50N","6370.079","-3429.134","270","RES, 33 OHM, 1%, 1/8W, TF, 0805"
"R20","CRCW080533R0FKEA","TopLayer","RESC2012X50N","6551.181","-3425.197","270","RES, 33 OHM, 1%, 1/8W, TF, 0805"
"R19","CRCW080533R0FKEA","TopLayer","RESC2012X50N","5361.624","-3478.796","0","RES, 33 OHM, 1%, 1/8W, TF, 0805"
"R18","CRCW080533R0FKEA","TopLayer","RESC2012X50N","5365.561","-3317.379","0","RES, 33 OHM, 1%, 1/8W, TF, 0805"
"R9","1.21_1%_0402","TopLayer","RESC1005X40X25LL10T10","5944.882","-2299.213","90",""
"R8","2mOhm_1%_1206","TopLayer","RESC3216X89X64NL25T25","6409.449","-2059.055","90",""
"R7","2mOhm_1%_1206","TopLayer","RESC3216X89X64NL25T25","5767.717","-1452.756","90",""
"R6","2.21_1%_0402","TopLayer","RESC1005X40X25ML05T10","6066.929","-2322.835","180",""
"R4","1.21_1%_0402","TopLayer","RESC0402(1005)_N","6169.291","-2397.638","0","1R21 0.063W 1% 0402 (1005 Metric)  SMD"
"R3","4.7K_0402","TopLayer","RESC1005X40X25LL05T05","5629.921","-2055.118","0","Chip Resistor, 4.7 KOhm, +/- 1%, 0.1 W, -55 to 155 degC, 0402 (1005 Metric), RoHS, Tape and Reel"
"R2","4.7K_0402","TopLayer","RESC1005X40X25LL05T05","5629.921","-2090.551","0","Chip Resistor, 4.7 KOhm, +/- 1%, 0.1 W, -55 to 155 degC, 0402 (1005 Metric), RoHS, Tape and Reel"
"R1","200_1%_0402","TopLayer","FP-ERJ2RK-IPC_A","6862.205","-3224.409","180","RES SMD 200 OHM 1% 1/10W 0402"
"P2","PCIex4","TopLayer","PCIE_4LANE_EDGE","2161.417","-4004.518","0","PCIE x4 Edge Connector,OrCAD Symbol,NC"
"L2","2.2uH_10A","TopLayer","FP-IHLP-2525EZ-FP_2_413x3-MFG","6129.921","-2759.843","0","Commercial Inductors, High Saturation Series 2.2uH 10A 13.6mO 20%"
"L1","2.2uH_10A","TopLayer","FP-IHLP-2525EZ-FP_2_413x3-MFG","6165.354","-2157.480","0","Commercial Inductors, High Saturation Series 2.2uH 10A 13.6mO 20%"
"F1","FUSE_0603_5.00A","TopLayer","FUSM1608X60N","5948.819","-1594.488","180","FUSE SLOW 5.00A 32V M 0603"
"D14","155124M173200","TopLayer","155124M173200","-190.453","-1084.646","90","LED (Multiple)"
"D13","155124M173200","TopLayer","155124M173200","-190.453","-651.575","90","LED (Multiple)"
"D11","BLUE","TopLayer","FP-LTST-C191TBKT-MFG","472.441","118.110","90","LED BLUE CLEAR CHIP SMD"
"D8","BAT54SW","TopLayer","SOT65P210X110-3N","6370.079","-3248.032","270","DIO, SCHOTTKY, BAT54S, DUAL SERIES, 30V, 200MA, SC-70"
"D7","BAT54SW","TopLayer","SOT65P210X110-3N","6557.087","-3249.016","270","DIO, SCHOTTKY, BAT54S, DUAL SERIES, 30V, 200MA, SC-70"
"D6","BAT54SW","TopLayer","SOT65P210X110-3N","5195.286","-3478.796","0","DIO, SCHOTTKY, BAT54S, DUAL SERIES, 30V, 200MA, SC-70"
"D5","BAT54SW","TopLayer","SOT65P210X110-3N","5196.270","-3317.379","0","DIO, SCHOTTKY, BAT54S, DUAL SERIES, 30V, 200MA, SC-70"
"D4","SML-LX0603IW-TR","TopLayer","FP-SML-LX0603IW-TR-MFG","6728.346","-3232.284","180","LED RED DIFFUSED SMD"
"C63","0.1uF","TopLayer","CAPC1608X87X45ML20T05","3481.060","-1014.822","270","C0603X104K5RACAUTO"
"C62","CAP_0805_10UF_25V","TopLayer","CAPC2012X14N","3574.803","-1003.937","90","CAP, CER, 10.UF, 25V, 10%, X5R, 0805"
"C61","0.1uF","TopLayer","CAPC1608X87X45ML20T05","984.252","-953.244","90","C0603X104K5RACAUTO"
"C60","10uF","TopLayer","FP-MK212BG-MFG","895.669","-943.402","270","None"
"C59","0.1uF","TopLayer","CAPC1608X87X45ML20T05","1141.732","-766.236","90","C0603X104K5RACAUTO"
"C58","10uF","TopLayer","FP-MK212BG-MFG","1230.315","-760.331","270","None"
"C53","CAP_0402_0.1UF_50V","BottomLayer","CAPC1005X06N","2734.410","-3806.000","90","CAP, CER, 0.1UF, 50V, 10%, X7R, AEC-Q200, 0402"
"C52","CAP_0402_0.1UF_50V","BottomLayer","CAPC1005X06N","2694.410","-3806.000","90","CAP, CER, 0.1UF, 50V, 10%, X7R, AEC-Q200, 0402"
"C51","CAP_0402_0.1UF_50V","BottomLayer","CAPC1005X06N","2569.410","-3806.000","90","CAP, CER, 0.1UF, 50V, 10%, X7R, AEC-Q200, 0402"
"C50","CAP_0402_0.1UF_50V","BottomLayer","CAPC1005X06N","2534.410","-3806.000","90","CAP, CER, 0.1UF, 50V, 10%, X7R, AEC-Q200, 0402"
"C49","CAP_0402_0.1UF_50V","BottomLayer","CAPC1005X06N","2419.410","-3806.000","90","CAP, CER, 0.1UF, 50V, 10%, X7R, AEC-Q200, 0402"
"C48","CAP_0402_0.1UF_50V","BottomLayer","CAPC1005X06N","2379.410","-3806.000","90","CAP, CER, 0.1UF, 50V, 10%, X7R, AEC-Q200, 0402"
"C47","CAP_0402_0.1UF_50V","BottomLayer","CAPC1005X06N","2226.410","-3806.000","90","CAP, CER, 0.1UF, 50V, 10%, X7R, AEC-Q200, 0402"
"C46","CAP_0402_0.1UF_50V","BottomLayer","CAPC1005X06N","2183.410","-3806.000","90","CAP, CER, 0.1UF, 50V, 10%, X7R, AEC-Q200, 0402"
"C45","CAP_0402_0.1UF_50V","BottomLayer","CAPC1005X06N","2104.410","-3806.000","90","CAP, CER, 0.1UF, 50V, 10%, X7R, AEC-Q200, 0402"
"C44","CAP_0402_0.1UF_50V","BottomLayer","CAPC1005X06N","2064.410","-3806.000","90","CAP, CER, 0.1UF, 50V, 10%, X7R, AEC-Q200, 0402"
"C22","10uF_16V_0603","TopLayer","FP-0603-L_1_6_0_2-W_0_8_0-MFG","6503.937","-2248.032","270","Multilayer Ceramic Capacitor 10uF 16V X5R 20% SMD 0603 T/R"
"C21","0.1uF_0402","TopLayer","CAPC1005X56X25NL10T15","6437.008","-2255.905","90",""
"C20","10uF_16V_0603","TopLayer","FP-0603-L_1_6_0_2-W_0_8_0-MFG","5346.457","-1338.583","180","Multilayer Ceramic Capacitor 10uF 16V X5R 20% SMD 0603 T/R"
"C19","0.1uF_0402","TopLayer","CAPC1005X56X25NL10T15","5342.520","-1413.386","0",""
"C18","0.1uF_25V_0402","TopLayer","FP-0402-L_1_0_1-W_0_5_0_1-IPC_C","6818.898","-2072.223","270","General Purpose Ceramic Capacitor, 0402, 100nF, 10%, X7R, 15%, 25V"
"C17","1uF_16V_0402","TopLayer","FP-0402-L_1_0_0_05-W_0_5-IPC_A","6833.617","-1851.796","90","None"
"C16","2.2uF_16V_0402","TopLayer","FP-C1005-050-0_05-IPC_A","6669.291","-2074.803","270","Multilayer Ceramic Capacitors 2.2µF ±10% 16V X5R SMD 0402"
"C15","10uF_16V_0603","TopLayer","FP-0603-L_1_6_0_2-W_0_8_0-MFG","6744.095","-2074.803","270","Multilayer Ceramic Capacitor 10uF 16V X5R 20% SMD 0603 T/R"
"C14","100uF_16V_2917","TopLayer","FP-T495D107K016ATE125-MFG","6602.362","-1834.646","270","CAP TANT 100UF 10% 16V 2917"
"C13","47uF_16V_1206","TopLayer","FP-C3216-160-0_2-MFG","6755.905","-1846.457","90","Multilayer Ceramic Capacitors 47uF ±20% 16V X5R SMD 1206"
"C12","4.7uF_50V_1206","TopLayer","FP-GRM31C-0_2-e0_3_0_8-IPC_C","5866.142","-1885.827","90","Chip Multilayer Ceramic Capacitors for General Purpose, 1206, 4.7uF, X7R, 15%, 10%, 50V"
"C11","4.7uF_50V_1206","TopLayer","FP-GRM31C-0_2-e0_3_0_8-IPC_C","5960.630","-1885.827","90","Chip Multilayer Ceramic Capacitors for General Purpose, 1206, 4.7uF, X7R, 15%, 10%, 50V"
"C10","100uF_16V_2917","TopLayer","FP-T495D107K016ATE125-MFG","6173.228","-1913.386","180","CAP TANT 100UF 10% 16V 2917"
"C9","0.1uF_50V_0603","TopLayer","FP-CC0603-DA-MFG","5992.126","-2397.638","270","CAP CER 0.1UF 50V X7R 0603"
"C8","4.7nF_50V_0402","TopLayer","FP-CC0402-MFG","5602.362","-1996.063","270","CAP CER 4700PF 50V X7R 0402"
"C7","DNI_1nF_50V_0402","TopLayer","FP-CL180-IPC_C","5913.386","-2374.016","180","Cap Ceramic 1nF 50V C0G ±5% SMD 0402 +125°C Paper T/R"
"C6","0.1uF_25V_0402","TopLayer","FP-0402-L_1_0_1-W_0_5_0_1-IPC_C","5625.984","-2145.669","90","General Purpose Ceramic Capacitor, 0402, 100nF, 10%, X7R, 15%, 25V"
"C5","2.2uF_16V_0402","TopLayer","FP-C1005-050-0_05-IPC_A","5535.433","-2232.284","90","Multilayer Ceramic Capacitors 2.2µF ±10% 16V X5R SMD 0402"
"C4","1uF_16V_0402","TopLayer","FP-0402-L_1_0_0_05-W_0_5-IPC_A","5614.173","-2216.535","180","None"
"C3","0.1uF_50V_0603","TopLayer","FP-CC0603-DA-MFG","6169.291","-2334.646","180","CAP CER 0.1UF 50V X7R 0603"
"C2","0.1uF","TopLayer","CAPC1608X87X45ML20T05","5681.102","-1204.724","270","C0603X104K5RACAUTO"
"C1","CAP_0805_10UF_25V","TopLayer","CAPC2012X14N","5775.591","-1208.661","90","CAP, CER, 10.UF, 25V, 10%, X5R, 0805"
